# S9S_MB_2U (Grand Teton) — schematic netlist excerpt (pin names and nets, part order shuffled) for the footprints in the layout excerpt that follows; sources: Cadence DE-HDL packaged netlist, KiCad conversion of 03242023_DA0F0TMBIJ0_F0T_Motherboard_J_brd_V01_OCP.brd

R3171  Q_RES  0 5% CHIP  pkg 0402LF  page 159 : A = OCP_V3_2_ISO_BIF2_EN ; B = OCP_V3_2_BIF2_R_N
PR3830  Q_RES  10 1% EMPTY  pkg 0402LF  page 162 : A = P12V_AUX ; B = P12V_OCP_VCC_2

(kicad_pcb
	(version 20260206)
	(generator "pcbnew")
	(generator_version "10.0")
	(general
		(thickness 1.6)
		(legacy_teardrops no)
	)
	(paper "A4")
	(title_block
		(title "03242023_DA0F0TMBIJ0_F0T_Motherboard_J_brd_V01_OCP.brd")
		(comment 1 "Grand Teton / footprints 4124-4125 of 6105")
	)
	(layers
		(0 "F.Cu" signal "TOP")
		(4 "In1.Cu" signal "GND")
		(6 "In2.Cu" signal "IN1")
		(8 "In3.Cu" signal "GND1")
		(10 "In4.Cu" signal "IN2")
		(12 "In5.Cu" signal "GND2")
		(14 "In6.Cu" signal "IN3")
		(16 "In7.Cu" signal "GND3")
		(18 "In8.Cu" signal "VCC")
		(20 "In9.Cu" signal "VCC1")
		(22 "In10.Cu" signal "GND4")
		(24 "In11.Cu" signal "IN4")
		(26 "In12.Cu" signal "GND5")
		(28 "In13.Cu" signal "IN5")
		(30 "In14.Cu" signal "GND6")
		(32 "In15.Cu" signal "IN6")
		(34 "In16.Cu" signal "GND7")
		(2 "B.Cu" signal "BOTTOM")
		(9 "F.Adhes" user "F.Adhesive")
		(11 "B.Adhes" user "B.Adhesive")
		(13 "F.Paste" user "Package Geometry/Pastemask Top")
		(15 "B.Paste" user "Package Geometry/Pastemask Bottom")
		(5 "F.SilkS" user "Ref Des/Silkscreen Top")
		(7 "B.SilkS" user "Ref Des/Silkscreen Bottom")
		(1 "F.Mask" user "Board Geometry/Soldermask Top")
		(3 "B.Mask" user "Board Geometry/Soldermask Bottom")
		(17 "Dwgs.User" user "User.Drawings")
		(19 "Cmts.User" user "User.Comments")
		(21 "Eco1.User" user "User.Eco1")
		(23 "Eco2.User" user "User.Eco2")
		(25 "Edge.Cuts" user "Board Geometry/Outline")
		(27 "Margin" user)
		(31 "F.CrtYd" user "Package Geometry/Place Bound Top")
		(29 "B.CrtYd" user "Package Geometry/Place Bound Bottom")
		(35 "F.Fab" user "Ref Des/Assembly Top")
		(33 "B.Fab" user "Ref Des/Assembly Bottom")
	)
	(footprint ""
		(layer "F.Cu")
		(at 61.26988 -16.220948 -90)
		(property "Reference" "R3171"
			(at 0 0 270)
			(layer "F.SilkS")
			(hide yes)
			(effects
				(font
					(size 1.27 1.27)
				)
			)
		)
		(property "Value" ""
			(at 0 0 270)
			(layer "F.Fab")
			(effects
				(font
					(size 1.27 1.27)
				)
			)
		)
		(duplicate_pad_numbers_are_jumpers no)
		(fp_line
			(start -0.7874 0.4064)
			(end -0.7874 -0.4064)
			(stroke
				(width 0.1524)
				(type default)
			)
			(layer "F.SilkS")
		)
		(fp_line
			(start 0.7874 0.4064)
			(end -0.7874 0.4064)
			(stroke
				(width 0.1524)
				(type default)
			)
			(layer "F.SilkS")
		)
		(fp_line
			(start -0.7874 -0.4064)
			(end 0.7874 -0.4064)
			(stroke
				(width 0.1524)
				(type default)
			)
			(layer "F.SilkS")
		)
		(fp_line
			(start 0.7874 -0.4064)
			(end 0.7874 0.4064)
			(stroke
				(width 0.1524)
				(type default)
			)
			(layer "F.SilkS")
		)
		(fp_line
			(start -0.67945 0.3048)
			(end -0.67945 -0.305054)
			(stroke
				(width 0.1)
				(type default)
			)
			(layer "F.Fab")
		)
		(fp_line
			(start -0.12065 0.3048)
			(end -0.67945 0.3048)
			(stroke
				(width 0.1)
				(type default)
			)
			(layer "F.Fab")
		)
		(fp_line
			(start 0.120396 0.3048)
			(end 0.120396 0.2794)
			(stroke
				(width 0.1)
				(type default)
			)
			(layer "F.Fab")
		)
		(fp_line
			(start 0.67945 0.3048)
			(end 0.120396 0.3048)
			(stroke
				(width 0.1)
				(type default)
			)
			(layer "F.Fab")
		)
		(fp_line
			(start -0.12065 0.2794)
			(end -0.12065 0.3048)
			(stroke
				(width 0.1)
				(type default)
			)
			(layer "F.Fab")
		)
		(fp_line
			(start 0.120396 0.2794)
			(end -0.12065 0.2794)
			(stroke
				(width 0.1)
				(type default)
			)
			(layer "F.Fab")
		)
		(fp_line
			(start -0.12065 -0.2794)
			(end 0.12065 -0.2794)
			(stroke
				(width 0.1)
				(type default)
			)
			(layer "F.Fab")
		)
		(fp_line
			(start 0.12065 -0.2794)
			(end 0.12065 -0.3048)
			(stroke
				(width 0.1)
				(type default)
			)
			(layer "F.Fab")
		)
		(fp_line
			(start 0.12065 -0.3048)
			(end 0.67945 -0.3048)
			(stroke
				(width 0.1)
				(type default)
			)
			(layer "F.Fab")
		)
		(fp_line
			(start 0.67945 -0.3048)
			(end 0.67945 0.3048)
			(stroke
				(width 0.1)
				(type default)
			)
			(layer "F.Fab")
		)
		(fp_line
			(start -0.67945 -0.305054)
			(end -0.12065 -0.305054)
			(stroke
				(width 0.1)
				(type default)
			)
			(layer "F.Fab")
		)
		(fp_line
			(start -0.12065 -0.305054)
			(end -0.12065 -0.2794)
			(stroke
				(width 0.1)
				(type default)
			)
			(layer "F.Fab")
		)
		(pad "1" smd circle
			(at -0.40005 0 270)
			(size 0 0)
			(layers "F.Cu" "F.Mask" "F.Paste")
			(net "OCP_V3_2_ISO_BIF2_EN")
		)
		(pad "2" smd circle
			(at 0.40005 0 270)
			(size 0 0)
			(layers "F.Cu" "F.Mask" "F.Paste")
			(net "OCP_V3_2_BIF2_R_N")
		)
	)
	(footprint ""
		(layer "F.Cu")
		(at 77.55001 -24.713946 -90)
		(property "Reference" "PR3830"
			(at 0 0 270)
			(layer "F.SilkS")
			(hide yes)
			(effects
				(font
					(size 1.27 1.27)
				)
			)
		)
		(property "Value" ""
			(at 0 0 270)
			(layer "F.Fab")
			(effects
				(font
					(size 1.27 1.27)
				)
			)
		)
		(duplicate_pad_numbers_are_jumpers no)
		(fp_line
			(start -0.7874 0.4064)
			(end -0.7874 -0.4064)
			(stroke
				(width 0.1524)
				(type default)
			)
			(layer "F.SilkS")
		)
		(fp_line
			(start 0.7874 0.4064)
			(end -0.7874 0.4064)
			(stroke
				(width 0.1524)
				(type default)
			)
			(layer "F.SilkS")
		)
		(fp_line
			(start -0.7874 -0.4064)
			(end 0.7874 -0.4064)
			(stroke
				(width 0.1524)
				(type default)
			)
			(layer "F.SilkS")
		)
		(fp_line
			(start 0.7874 -0.4064)
			(end 0.7874 0.4064)
			(stroke
				(width 0.1524)
				(type default)
			)
			(layer "F.SilkS")
		)
		(fp_line
			(start -0.67945 0.3048)
			(end -0.67945 -0.305054)
			(stroke
				(width 0.1)
				(type default)
			)
			(layer "F.Fab")
		)
		(fp_line
			(start -0.12065 0.3048)
			(end -0.67945 0.3048)
			(stroke
				(width 0.1)
				(type default)
			)
			(layer "F.Fab")
		)
		(fp_line
			(start 0.120396 0.3048)
			(end 0.120396 0.2794)
			(stroke
				(width 0.1)
				(type default)
			)
			(layer "F.Fab")
		)
		(fp_line
			(start 0.67945 0.3048)
			(end 0.120396 0.3048)
			(stroke
				(width 0.1)
				(type default)
			)
			(layer "F.Fab")
		)
		(fp_line
			(start -0.12065 0.2794)
			(end -0.12065 0.3048)
			(stroke
				(width 0.1)
				(type default)
			)
			(layer "F.Fab")
		)
		(fp_line
			(start 0.120396 0.2794)
			(end -0.12065 0.2794)
			(stroke
				(width 0.1)
				(type default)
			)
			(layer "F.Fab")
		)
		(fp_line
			(start -0.12065 -0.2794)
			(end 0.12065 -0.2794)
			(stroke
				(width 0.1)
				(type default)
			)
			(layer "F.Fab")
		)
		(fp_line
			(start 0.12065 -0.2794)
			(end 0.12065 -0.3048)
			(stroke
				(width 0.1)
				(type default)
			)
			(layer "F.Fab")
		)
		(fp_line
			(start 0.12065 -0.3048)
			(end 0.67945 -0.3048)
			(stroke
				(width 0.1)
				(type default)
			)
			(layer "F.Fab")
		)
		(fp_line
			(start 0.67945 -0.3048)
			(end 0.67945 0.3048)
			(stroke
				(width 0.1)
				(type default)
			)
			(layer "F.Fab")
		)
		(fp_line
			(start -0.67945 -0.305054)
			(end -0.12065 -0.305054)
			(stroke
				(width 0.1)
				(type default)
			)
			(layer "F.Fab")
		)
		(fp_line
			(start -0.12065 -0.305054)
			(end -0.12065 -0.2794)
			(stroke
				(width 0.1)
				(type default)
			)
			(layer "F.Fab")
		)
		(pad "1" smd circle
			(at -0.40005 0 270)
			(size 0 0)
			(layers "F.Cu" "F.Mask" "F.Paste")
			(net "P12V_AUX")
		)
		(pad "2" smd circle
			(at 0.40005 0 270)
			(size 0 0)
			(layers "F.Cu" "F.Mask" "F.Paste")
			(net "P12V_OCP_VCC_2")
		)
	)
)
